FILE_TYPE = CONNECTIVITY;
{Allegro Design Entry HDL 17.4-2019 S026 (4007227) 1/17/2022}
"PAGE_NUMBER" = 464;
0"NC";
1"GND\g";
2"GND\g";
3"GND\g";
4"GND\g";
5"SMB_RT_CPU1_P3_ROM_R_SCL";
6"SMB_RT_CPU1_P3_ROM_SCL";
7"SMB_RT_CPU1_P3_ROM_R_SDA";
8"P1V8_CPU1_RT_1D\g";
9"SMB_RT_CPU1_P3_ROM_SDA";
10"U21_E2";
%"P1V0"
"1","(-4750,6175)","0","pure_quanta_power","I18";
;
HDL_POWER"P1V8_CPU1_RT_1D"
CDS_LIB"pure_quanta_power";
"A"8;
%"Q_CAP"
"1","(-5000,5875)","0","pure_quanta","I19";
;
LOCATION"C7504"
$SEC"1"
CDS_SEC"1"
PACK_TYPE"C0201"
VALUE"0.1UF"
TOLERANCE"10%"
MATERIAL"X7S"
VOLTAGE"10V"
CDS_LIB"pure_quanta"
PART_NUMBER"CH4102K6E00";
"B"
$PN"2"1;
"A"
$PN"1"8;
%"UNIVERSAL_GND"
"1","(-5000,5650)","0","pure_quanta_power","I20";
;
CDS_LIB"pure_quanta_power"
HDL_POWER"GND";
"A"1;
%"UNIVERSAL_GND"
"1","(-4700,5450)","7","pure_quanta_power","I21";
;
CDS_LIB"pure_quanta_power"
HDL_POWER"GND";
"A"2;
%"Q_RES"
"2","(-3250,5250)","0","pure_quanta","I22";
;
LOCATION"R6791"
$SEC"1"
CDS_SEC"1"
PACK_TYPE"0201LF"
MATERIAL"CHIP"
VALUE"1K"
TOLERANCE"1%"
WATTAGE"1/20W"
CDS_LIB"pure_quanta"
PART_NUMBER"CS21001FE07";
"A"
$PN"1"10;
"B"
$PN"2"3;
%"UNIVERSAL_GND"
"1","(-3250,4900)","0","pure_quanta_power","I23";
;
CDS_LIB"pure_quanta_power"
HDL_POWER"GND";
"A"3;
%"UNIVERSAL_GND"
"1","(-3400,5175)","0","pure_quanta_power","I24";
;
CDS_LIB"pure_quanta_power"
HDL_POWER"GND";
"A"4;
%"Q_RES"
"1","(-5650,5400)","0","pure_quanta","I25";
;
LOCATION"R697"
SEC"1"
MATERIAL"CHIP"
PACK_TYPE"0201LF"
TOLERANCE"5%"
VALUE"0"
WATTAGE"1/20W"
CDS_LIB"pure_quanta"
SEC_TYPE"0201LF"
PART_NUMBER"CS00001JE10";
"B"
$PN"2"6;
"A"
$PN"1"5;
%"Q_RES"
"1","(-5650,5350)","0","pure_quanta","I4";
;
LOCATION"R698"
$SEC"1"
CDS_SEC"1"
VALUE"33.2"
TOLERANCE"1%"
PACK_TYPE"0201LF"
MATERIAL"CHIP"
WATTAGE"1/20W"
CDS_LIB"pure_quanta"
PART_NUMBER"CS03321FE09";
"B"
$PN"2"9;
"A"
$PN"1"7;
%"M24M02DRMN6TP"
"1","(-4225,5425)","0","pure_quanta","I5";
;
LOCATION"U21"
$SEC"1"
CDS_SEC"1"
MATERIAL"IC"
PART_TYPE"SMLF"
VALUE"M24M02-DRMN6TP"
NEEDS_NO_SIZE"TRUE"
CDS_LMAN_SYM_OUTLINE"-175,125,175,-125"
CDS_LIB"pure_quanta"
PART_NUMBER"AKE33Z00600";
"DU1"
$PN"1"0;
"DU2"
$PN"2"0;
"E2"
$PN"3"10;
"VSS"
$PN"4"4;
"SDA"
$PN"5"9;
"SCL"
$PN"6"6;
"WC_N \B"
$PN"7"2;
"VCC"
$PN"8"8;
END.
